# OCXO_DaughterCard_RakonRFP045.xlsx — OCXO_DaughterCard_RakonRFP045 (bom)
| Comment | Description | Designator | Footprint | LibRef | Quantity |
| Yageo_RC0402FR-07100RL | RES SMD 100 OHM 1% 1/16W 0402 | R5 | RESC1005X040N | RES-CMP-00538-3 | 1 |
| Yageo_RC0201JR-070RL | RES, 0.0 OHM, 0.5A, 1/20W, 0201 | R33 | RESC0603X026N | CMP-RES-00843-1 | 1 |
| Yageo_RC0201FR-0710KL | RES, 10K OHM, 1%, 1/20W, 200PPM/C, 0201 | R34 | RESC0603X026N | CMP-RES-00602-1 | 1 |
| Yageo_CC0402KRX7R7BB103 | CAP, CER, X7R, 0.01UF, 10%, 16V, 0402, 0.55MM T | C12, C14 | CAPC1005X055N | CAP-CMP-00257-3 | 2 |
| Wurth_9774040243R | STANDOFF, ROUND, M2X0.4 STEEL 4MM, 9774040243R | J1, J2 | TH000V_300DIAx400_001mt_9774040243R | CON-CMP-00164-1 | 2 |
| TI_DS90LV028AQMA/NOPB | IC, RVCR, DS90LV028AQ-Q1, DUAL, DIFF, LVDS, 400MBPS, SOIC-8 | U4 | SOP127P600X175_8N | INT-CMP-00017-4 | 1 |
| TI_DS90LV027AQMA/NOPB | IC, DRIVER, DS90LV027AQ, DUAL, DIFF, LVDS, 600MBPS, SOIC-8 | U3 | SOP127P600X175_8N | INT-CMP-00018-2 | 1 |
| TDK_MPZ1608S601ATA00 | FERRITE BEAD, 600 OHM @100MHZ, 25%, 1A, 0.150 OHM DCR, 0603, 0.95MM T | FL1, FL2 | INDC1608X095N | FER-CMP-00057-5 | 2 |
| Stackpole Electronics, Inc._RMCF1210ZT0R00 | RES, 0.0 OHM, 3A, 1/2W, 1210 | R1 | RESC3225X070N | RES-CMP-00829-3 | 1 |
| Stackpole Electronics, Inc._HCJ0402ZT0R00 | RES, 0.0 OHM, 1/8W, 6.5A, 0402 | R6, R7, R8 | RESC1005X045N | RES-CMP-00382-3 | 3 |
| Samtec_HTSW-102-07-T-S | CONN, PIN, HEADER, 2POS, 2.54MM PITCH, 8.38MM H, VERT, TIN, TH | P9 | TH002_254_508x254x838_000mt_HTSW | CON-CMP-00061-3 | 1 |
| Samsung Electro-Mechanics_CL05B104JO5NNNC | CAP, CER, X7R, 0.1UF, 5%, 16V, 0402, 0.55MM T | C1, C6, C7, C9, C11, C13, C17, C19, C21, C23 | CAPC1005X055N | CAP-CMP-00271-3, CMP-CAP-00082-2 | 10 |
| Rakon_RFPO45 US 10 LF | OSC, OCXO, RFPO45, 10 - 26MHZ, 10PPB STAB, HCMOS, 3.3V, 9.7X7.5X4.3MM, SMT | Y4 | OSC004_600_970x750x430_RFP045 | COR-CMP-00014-2 | 1 |
| Panasonic_ERJ-2RKF1003X | RES, 100K OHM, 1%, 1/10W, 100PPM/C, 0402 | R4 | RESC1005X040N | RES-CMP-00289-3 | 1 |
| NXP_PCT2075TP,147 | SENSOR DIGITAL -55C-125C 8HWSON | U5 | SON50P300X200X80-HS-9N_EP160x160_IPC | SNS-CMP-00004-1 | 1 |
| Murata_GRM188R61A106ME69D | CAP, CER, X5R, 10UF, 20%, 10V, 0603, 0.80MM T | C22 | CAPC1608X090N | CMP-CAP-00380-1 | 1 |
| Murata_GRM188D71A106MA73D | CAP, CER, X7T, 10UF, 20%, 10V, 0603, 1.00MM T | C8, C10, C18, C20 | CAPC1608X100N | CAP-CMP-00449-3 | 4 |
| Murata_GRM21BR61A226ME51L | CAP, CER, X5R, 22UF, 20%, 10V, 0805, 1.40MM T | C2, C3, C4 | CAPC2013X140N | CAP-CMP-00519-3 | 3 |
| Molex_539160208 | CONN, B2B/FPC, HEADER, 20-POS, 0.5MM PITCH, 4.0MM H, VERT, GOLD, SMT | P10 | SM020V_50_730x310x337_000mt_53916 | CON-CMP-00163-2 | 1 |
| Mill-Max_8600-0-05-80-00-00-03-0 | CONN, PC PIN, PRESS-FIT, 10.16MM LENGTH, TIN, TH | P1, P2, P3, P4, P5, P6, P7, P8, P11, P12 | TH001V_109DIA_000mt_8600-0 | CON-CMP-00162-1 | 10 |
| Microchip_AT24MAC602-XHM-B | IC, EEPROM, AT24MAC602, 2K-BIT (256 X 8), 1MHZ, I2C, 1.7V - 5.5V, TSSOP-8 | U2 | TSSOP65P640X120-8N | MEM-CMP-00010-1 | 1 |
| LMS1587IS-3.3/NOPB | 3A Low Dropout Fast Response Regulators, 3-pin TO-263, Pb-Free | U1 | KTT0003B_L | CMP-0062-00189-5 | 1 |
| Kemet_T491B476K010AT | CAP TANT 47UF 10% 10V 1411 | C5, C15, C16 | CAPMP3528X210N_T520 | CAP-CMP-00042-1 | 3 |
| 4871 | Round Standoff Threaded #2-56 Steel 0.063" (1.60mm) 1/16" | P13, P14, P15, P16 | Keystone_4871 | Keystone_4871 | 4 |
| 4.7K_1%_0402 | Chip Resistor, 4.7 KOhm, +/- 1%, 0.1 W, -55 to 155 degC, 0402 (1005 Metric), RoHS, Tape and Reel | R27, R28, R35, R36 | RESC1005X40X25LL05T05 | CMP-2002-01154-4 | 4 |
| 0_5%_0603 | Chip Resistor, 0 Ohm, +/- 5%, 0.1 W, -55 to 155 degC, 0603 (1608 Metric), RoHS, Tape and Reel | R16, R23 | RESC1608X55X25ML10T15 | CMP-2100-03667-1 | 2 |
| 0_1%_0402 |  | R11, R12, R17, R18, R19, R24, R25, R26, R30, R32 | RESC1005X40X25NL05T10 | CMP-1011-00001-2 | 10 |
